# S9S_MB_2U (Grand Teton) — schematic netlist excerpt (pin names and nets, part order shuffled) for the footprints in the layout excerpt that follows; sources: Cadence DE-HDL packaged netlist, KiCad conversion of 03242023_DA0F0TMBIJ0_F0T_Motherboard_J_brd_V01_OCP.brd

PJ42  SCONN21_9193031121LF  SCONN21_91930-31121LF EMPTY  pkg CON_F21S2H2D2S_P1W4-22_LDH  page 305
  \1\  = P12V_PSU
  \2\  = P12V_HSC_SENSE1_P
  \3\  = P12V_HSC_SENSE1_N
  \4\  = P12V_HSC_SENSE2_P
  \5\  = P12V_HSC_SENSE2_N
  \6\  = P12V_HSC_ADC_N
  \7\  = P12V_HSC_ADC_P
  \8\  = P12V_HSC_GATE1
  \9\  = P12V_HSC_GATE2
  \10\  = P12V_AUX
  \11\  = GND
  \12\  = P3V3_AUX
  \13\  = IRQ_HSC_FAULT_N
  \14\  = HSC_EN
  \15\  = MB0_P12V_STBY_PWRGD
  \16\  = HSC_CSOUT
  \17\  = HSC_TYPE_ADC
  \18\  = SMB_SML1_PMBUS_HSC_MODULE_SCL
  \19\  = SMB_SML1_PMBUS_HSC_MODULE_SDA
  \20\  = IRQ_SML1_PMBUS_ALERT_N
  \21\  = GND
  G1  = GND
  G2  = GND

(kicad_pcb
	(version 20260206)
	(generator "pcbnew")
	(generator_version "10.0")
	(general
		(thickness 1.6)
		(legacy_teardrops no)
	)
	(paper "A4")
	(title_block
		(title "03242023_DA0F0TMBIJ0_F0T_Motherboard_J_brd_V01_OCP.brd")
		(comment 1 "Grand Teton / footprint 2347 of 6105 (PJ42), pads 1-25 of 25")
	)
	(layers
		(0 "F.Cu" signal "TOP")
		(4 "In1.Cu" signal "GND")
		(6 "In2.Cu" signal "IN1")
		(8 "In3.Cu" signal "GND1")
		(10 "In4.Cu" signal "IN2")
		(12 "In5.Cu" signal "GND2")
		(14 "In6.Cu" signal "IN3")
		(16 "In7.Cu" signal "GND3")
		(18 "In8.Cu" signal "VCC")
		(20 "In9.Cu" signal "VCC1")
		(22 "In10.Cu" signal "GND4")
		(24 "In11.Cu" signal "IN4")
		(26 "In12.Cu" signal "GND5")
		(28 "In13.Cu" signal "IN5")
		(30 "In14.Cu" signal "GND6")
		(32 "In15.Cu" signal "IN6")
		(34 "In16.Cu" signal "GND7")
		(2 "B.Cu" signal "BOTTOM")
		(9 "F.Adhes" user "F.Adhesive")
		(11 "B.Adhes" user "B.Adhesive")
		(13 "F.Paste" user "Package Geometry/Pastemask Top")
		(15 "B.Paste" user "Package Geometry/Pastemask Bottom")
		(5 "F.SilkS" user "Ref Des/Silkscreen Top")
		(7 "B.SilkS" user "Ref Des/Silkscreen Bottom")
		(1 "F.Mask" user "Board Geometry/Soldermask Top")
		(3 "B.Mask" user "Board Geometry/Soldermask Bottom")
		(17 "Dwgs.User" user "User.Drawings")
		(19 "Cmts.User" user "User.Comments")
		(21 "Eco1.User" user "User.Eco1")
		(23 "Eco2.User" user "User.Eco2")
		(25 "Edge.Cuts" user "Board Geometry/Outline")
		(27 "Margin" user)
		(31 "F.CrtYd" user "Package Geometry/Place Bound Top")
		(29 "B.CrtYd" user "Package Geometry/Place Bound Bottom")
		(35 "F.Fab" user "Ref Des/Assembly Top")
		(33 "B.Fab" user "Ref Des/Assembly Bottom")
	)
	(footprint ""
		(layer "F.Cu")
		(at 292.98011 -390.459976 -90)
		(property "Reference" "PJ42"
			(at 2.072132 -8.52297 90)
			(unlocked yes)
			(layer "F.SilkS")
			(effects
				(font
					(size 0.7874 0.5842)
					(thickness 0.1524)
				)
				(justify left)
			)
		)
		(property "Value" ""
			(at 0 0 270)
			(layer "F.Fab")
			(effects
				(font
					(size 1.27 1.27)
				)
			)
		)
		(duplicate_pad_numbers_are_jumpers no)
		(pad "" np_thru_hole circle
			(at 1.100074 -5.5245 180)
			(size 0.762 0.762)
			(drill 0.762)
			(layers "*.Cu" "*.Mask")
			(clearance 0.381)
			(thermal_gap 0.381)
		)
		(pad "" np_thru_hole circle
			(at 1.100074 5.5245 180)
			(size 0.762 0.762)
			(drill 0.762)
			(layers "*.Cu" "*.Mask")
			(clearance 0.381)
			(thermal_gap 0.381)
		)
		(pad "1" smd rect
			(at -2.109978 -4.99999)
			(size 0.6096 1.651)
			(layers "F.Cu" "F.Mask" "F.Paste")
			(net "P12V_PSU")
		)
		(pad "2" smd rect
			(at -2.109978 -3.999992)
			(size 0.6096 1.651)
			(layers "F.Cu" "F.Mask" "F.Paste")
			(net "P12V_HSC_SENSE1_P")
		)
		(pad "3" smd rect
			(at -2.109978 -2.999994)
			(size 0.6096 1.651)
			(layers "F.Cu" "F.Mask" "F.Paste")
			(net "P12V_HSC_SENSE1_N")
		)
		(pad "4" smd rect
			(at -2.109978 -1.999996)
			(size 0.6096 1.651)
			(layers "F.Cu" "F.Mask" "F.Paste")
			(net "P12V_HSC_SENSE2_P")
		)
		(pad "5" smd rect
			(at -2.109978 -0.999998)
			(size 0.6096 1.651)
			(layers "F.Cu" "F.Mask" "F.Paste")
			(net "P12V_HSC_SENSE2_N")
		)
		(pad "6" smd rect
			(at -2.109978 0)
			(size 0.6096 1.651)
			(layers "F.Cu" "F.Mask" "F.Paste")
			(net "P12V_HSC_ADC_N")
		)
		(pad "7" smd rect
			(at -2.109978 0.999998)
			(size 0.6096 1.651)
			(layers "F.Cu" "F.Mask" "F.Paste")
			(net "P12V_HSC_ADC_P")
		)
		(pad "8" smd rect
			(at -2.109978 1.999996)
			(size 0.6096 1.651)
			(layers "F.Cu" "F.Mask" "F.Paste")
			(net "P12V_HSC_GATE1")
		)
		(pad "9" smd rect
			(at -2.109978 2.999994)
			(size 0.6096 1.651)
			(layers "F.Cu" "F.Mask" "F.Paste")
			(net "P12V_HSC_GATE2")
		)
		(pad "10" smd rect
			(at -2.109978 3.999992)
			(size 0.6096 1.651)
			(layers "F.Cu" "F.Mask" "F.Paste")
			(net "P12V_AUX")
		)
		(pad "11" smd rect
			(at -2.109978 4.99999)
			(size 0.6096 1.651)
			(layers "F.Cu" "F.Mask" "F.Paste")
			(net "GND")
		)
		(pad "12" smd rect
			(at 2.109978 -4.500118 180)
			(size 0.6096 1.651)
			(layers "F.Cu" "F.Mask" "F.Paste")
			(net "P3V3_AUX")
		)
		(pad "13" smd rect
			(at 2.109978 -3.50012 180)
			(size 0.6096 1.651)
			(layers "F.Cu" "F.Mask" "F.Paste")
			(net "IRQ_HSC_FAULT_N")
		)
		(pad "14" smd rect
			(at 2.109978 -2.500122 180)
			(size 0.6096 1.651)
			(layers "F.Cu" "F.Mask" "F.Paste")
			(net "HSC_EN")
		)
		(pad "15" smd rect
			(at 2.109978 -1.500124 180)
			(size 0.6096 1.651)
			(layers "F.Cu" "F.Mask" "F.Paste")
			(net "MB0_P12V_STBY_PWRGD")
		)
		(pad "16" smd rect
			(at 2.109978 -0.499872 180)
			(size 0.6096 1.651)
			(layers "F.Cu" "F.Mask" "F.Paste")
			(net "HSC_CSOUT")
		)
		(pad "17" smd rect
			(at 2.109978 0.499872 180)
			(size 0.6096 1.651)
			(layers "F.Cu" "F.Mask" "F.Paste")
			(net "HSC_TYPE_ADC")
		)
		(pad "18" smd rect
			(at 2.109978 1.500124 180)
			(size 0.6096 1.651)
			(layers "F.Cu" "F.Mask" "F.Paste")
			(net "SMB_SML1_PMBUS_HSC_MODULE_SCL")
		)
		(pad "19" smd rect
			(at 2.109978 2.500122 180)
			(size 0.6096 1.651)
			(layers "F.Cu" "F.Mask" "F.Paste")
			(net "SMB_SML1_PMBUS_HSC_MODULE_SDA")
		)
		(pad "20" smd rect
			(at 2.109978 3.50012 180)
			(size 0.6096 1.651)
			(layers "F.Cu" "F.Mask" "F.Paste")
			(net "IRQ_SML1_PMBUS_ALERT_N")
		)
		(pad "21" smd rect
			(at 2.109978 4.500118 180)
			(size 0.6096 1.651)
			(layers "F.Cu" "F.Mask" "F.Paste")
			(net "GND")
		)
		(pad "G1" smd circle
			(at 0 -6.720078 180)
			(size 0 0)
			(layers "F.Cu" "F.Mask" "F.Paste")
			(net "GND")
		)
		(pad "G2" smd circle
			(at 0 6.720078 180)
			(size 0 0)
			(layers "F.Cu" "F.Mask" "F.Paste")
			(net "GND")
		)
	)
)
